# BASEBOARD_FAB2 (Tioga Pass) — schematic netlist excerpt (pin names and nets, part order shuffled) for the footprints in the layout excerpt that follows; sources: Cadence DE-HDL packaged netlist, KiCad conversion of Wiwynn_Tioga_Pass_MB.brd

U8F3  SN74LVC2G07DCKR-GP  pkg DISCRET-G4  page 156
  \1a\  = RST_BMC_SYSRST_BTN_OUT_N
  GND  = GND
  \2a\  = FM_BMC_PWRBTN_OUT_N
  \2y\  = FM_PCH_PWRBTN_R_N
  VCC  = P3V3_STBY
  \1y\  = RST_BMC_SYSRST_BTN_OUT_B_R_N

R4P11  RES  100.0 1% CHIP  pkg 0402  page 21 : A = A_CPU0_ABC_RCOMP2 ; B = GND

(kicad_pcb
	(version 20260206)
	(generator "pcbnew")
	(generator_version "10.0")
	(general
		(thickness 1.6)
		(legacy_teardrops no)
	)
	(paper "A4")
	(title_block
		(title "Wiwynn_Tioga_Pass_MB.brd")
		(comment 1 "Tioga Pass / footprints 4391-4392 of 4770")
	)
	(layers
		(0 "F.Cu" signal "TOP")
		(4 "In1.Cu" signal "L2GND")
		(6 "In2.Cu" signal "L3")
		(8 "In3.Cu" signal "L4GND")
		(10 "In4.Cu" signal "L5")
		(12 "In5.Cu" signal "L6GND")
		(14 "In6.Cu" signal "L7VCC")
		(16 "In7.Cu" signal "L8VCC")
		(18 "In8.Cu" signal "L9GND")
		(20 "In9.Cu" signal "L10")
		(22 "In10.Cu" signal "L11GND")
		(24 "In11.Cu" signal "L12")
		(26 "In12.Cu" signal "L13GND")
		(2 "B.Cu" signal "BOTTOM")
		(9 "F.Adhes" user "F.Adhesive")
		(11 "B.Adhes" user "B.Adhesive")
		(13 "F.Paste" user "Package Geometry/Pastemask Top")
		(15 "B.Paste" user "Package Geometry/Pastemask Bottom")
		(5 "F.SilkS" user "Ref Des/Silkscreen Top")
		(7 "B.SilkS" user "Ref Des/Silkscreen Bottom")
		(1 "F.Mask" user "Board Geometry/Soldermask Top")
		(3 "B.Mask" user "Board Geometry/Soldermask Bottom")
		(17 "Dwgs.User" user "User.Drawings")
		(19 "Cmts.User" user "User.Comments")
		(21 "Eco1.User" user "User.Eco1")
		(23 "Eco2.User" user "User.Eco2")
		(25 "Edge.Cuts" user "Board Geometry/Outline")
		(27 "Margin" user)
		(31 "F.CrtYd" user "Package Geometry/Place Bound Top")
		(29 "B.CrtYd" user "Package Geometry/Place Bound Bottom")
		(35 "F.Fab" user "Ref Des/Assembly Top")
		(33 "B.Fab" user "Ref Des/Assembly Bottom")
	)
	(footprint ""
		(layer "B.Cu")
		(at 395.7828 -27.92476 90)
		(property "Reference" "U8F3"
			(at 0 0 90)
			(layer "B.SilkS")
			(hide yes)
			(effects
				(font
					(size 1.27 1.27)
				)
				(justify mirror)
			)
		)
		(property "Value" "*"
			(at 2.3622 -8.3185 90)
			(unlocked yes)
			(layer "B.Fab")
			(hide yes)
			(effects
				(font
					(size 1.27 1.016)
					(thickness 0.1524)
				)
				(justify mirror)
			)
		)
		(property "Device Type" "SN74LVC2G07DCKR-GP_DISCRET-G4-A"
			(at 2.3622 -10.2235 90)
			(unlocked yes)
			(layer "B.Fab")
			(hide yes)
			(effects
				(font
					(size 1.27 1.016)
					(thickness 0.1524)
				)
				(justify mirror)
			)
		)
		(duplicate_pad_numbers_are_jumpers no)
		(fp_line
			(start 1.4478 -1.7018)
			(end 1.4478 1.7018)
			(stroke
				(width 0.1524)
				(type default)
			)
			(layer "B.SilkS")
		)
		(fp_line
			(start -1.4478 -1.7018)
			(end 1.4478 -1.7018)
			(stroke
				(width 0.1524)
				(type default)
			)
			(layer "B.SilkS")
		)
		(fp_line
			(start 1.4478 1.7018)
			(end -1.4478 1.7018)
			(stroke
				(width 0.1524)
				(type default)
			)
			(layer "B.SilkS")
		)
		(fp_line
			(start -1.4478 1.7018)
			(end -1.4478 -1.7018)
			(stroke
				(width 0.1524)
				(type default)
			)
			(layer "B.SilkS")
		)
		(fp_line
			(start 1.5494 1.7907)
			(end 1.5494 0.8255)
			(stroke
				(width 0.635)
				(type default)
			)
			(layer "B.SilkS")
		)
		(fp_line
			(start 0.5715 1.7907)
			(end 1.5494 1.7907)
			(stroke
				(width 0.635)
				(type default)
			)
			(layer "B.SilkS")
		)
		(fp_poly
			(pts
				(xy 1.81864 2.02184) (xy 2.17424 1.66624) (xy 2.39268 1.4478) (xy 2.41808 1.4224) (xy 2.42824 1.4224)
				(xy 2.42824 1.4478) (xy 2.42824 2.6162) (xy 2.413 2.6162) (xy 2.17424 2.37744)
			)
			(stroke
				(width 0)
				(type default)
			)
			(fill yes)
			(layer "B.SilkS")
		)
		(fp_poly
			(pts
				(xy 1.524 -1.778) (xy -1.524 -1.778) (xy -1.524 1.778) (xy 1.524 1.778)
			)
			(stroke
				(width 0)
				(type default)
			)
			(fill no)
			(layer "B.CrtYd")
		)
		(fp_poly
			(pts
				(xy 1.524 -1.778) (xy -1.524 -1.778) (xy -1.524 1.778) (xy 1.524 1.778)
			)
			(stroke
				(width 0)
				(type default)
			)
			(fill no)
			(layer "B.Fab")
		)
		(pad "1" smd rect
			(at 0.65024 0.9398 270)
			(size 0.4064 1.016)
			(layers "B.Cu" "B.Mask" "B.Paste")
			(net "RST_BMC_SYSRST_BTN_OUT_N")
		)
		(pad "2" smd rect
			(at 0 0.9398 270)
			(size 0.4064 1.016)
			(layers "B.Cu" "B.Mask" "B.Paste")
			(net "GND")
		)
		(pad "3" smd rect
			(at -0.65024 0.9398 270)
			(size 0.4064 1.016)
			(layers "B.Cu" "B.Mask" "B.Paste")
			(net "FM_BMC_PWRBTN_OUT_N")
		)
		(pad "4" smd rect
			(at -0.65024 -0.9398 270)
			(size 0.4064 1.016)
			(layers "B.Cu" "B.Mask" "B.Paste")
			(net "FM_PCH_PWRBTN_R_N")
		)
		(pad "5" smd rect
			(at 0 -0.9398 270)
			(size 0.4064 1.016)
			(layers "B.Cu" "B.Mask" "B.Paste")
			(net "P3V3_STBY")
		)
		(pad "6" smd rect
			(at 0.65024 -0.9398 270)
			(size 0.4064 1.016)
			(layers "B.Cu" "B.Mask" "B.Paste")
			(net "RST_BMC_SYSRST_BTN_OUT_B_R_N")
		)
	)
	(footprint ""
		(layer "B.Cu")
		(at 282.259024 -71.867014 -90)
		(property "Reference" "R4P11"
			(at 0 0 90)
			(layer "B.SilkS")
			(hide yes)
			(effects
				(font
					(size 1.27 1.27)
				)
				(justify mirror)
			)
		)
		(property "Value" ""
			(at 0 0 90)
			(layer "B.Fab")
			(effects
				(font
					(size 1.27 1.27)
				)
				(justify mirror)
			)
		)
		(duplicate_pad_numbers_are_jumpers no)
		(fp_rect
			(start 0.2794 0.9906)
			(end -0.2794 -0.1016)
			(stroke
				(width 0)
				(type default)
			)
			(fill no)
			(layer "B.CrtYd")
		)
		(fp_line
			(start -0.2794 0.9906)
			(end -0.2794 -0.1016)
			(stroke
				(width 0.1)
				(type default)
			)
			(layer "B.Fab")
		)
		(fp_line
			(start 0.2794 0.9906)
			(end -0.2794 0.9906)
			(stroke
				(width 0.1)
				(type default)
			)
			(layer "B.Fab")
		)
		(fp_line
			(start -0.2794 -0.1016)
			(end 0.2794 -0.1016)
			(stroke
				(width 0.1)
				(type default)
			)
			(layer "B.Fab")
		)
		(fp_line
			(start 0.2794 -0.1016)
			(end 0.2794 0.9906)
			(stroke
				(width 0.1)
				(type default)
			)
			(layer "B.Fab")
		)
		(pad "1" smd rect
			(at 0 0 90)
			(size 0.508 0.508)
			(layers "B.Cu" "B.Mask" "B.Paste")
			(net "A_CPU0_ABC_RCOMP2")
		)
		(pad "2" smd rect
			(at 0 0.889 90)
			(size 0.508 0.508)
			(layers "B.Cu" "B.Mask" "B.Paste")
			(net "GND")
		)
		(zone
			(layer "B.Cu")
			(hatch none 0.5)
			(connect_pads
				(clearance 0)
			)
			(min_thickness 0.25)
			(keepout
				(tracks allowed)
				(vias not_allowed)
				(pads allowed)
				(copperpour not_allowed)
				(footprints allowed)
			)
			(placement
				(enabled no)
				(sheetname "")
			)
			(fill
				(thermal_gap 0.5)
				(thermal_bridge_width 0.5)
				(island_removal_mode 0)
			)
			(polygon
				(pts
					(xy 281.624024 -71.613014) (xy 282.005024 -71.613014) (xy 282.005024 -72.121014) (xy 281.624024 -72.121014)
				)
			)
		)
		(zone
			(layer "B.Cu")
			(hatch none 0.5)
			(connect_pads
				(clearance 0)
			)
			(min_thickness 0.25)
			(keepout
				(tracks not_allowed)
				(vias allowed)
				(pads allowed)
				(copperpour not_allowed)
				(footprints allowed)
			)
			(placement
				(enabled no)
				(sheetname "")
			)
			(fill
				(thermal_gap 0.5)
				(thermal_bridge_width 0.5)
				(island_removal_mode 0)
			)
			(polygon
				(pts
					(xy 281.624024 -71.613014) (xy 282.005024 -71.613014) (xy 282.005024 -72.121014) (xy 281.624024 -72.121014)
				)
			)
		)
	)
)
